FILE_TYPE = CONNECTIVITY;
{Allegro Design Entry HDL 16.6-p007 (v16-6-112F) 10/10/2012}
"PAGE_NUMBER" = 251;
0"NC";
1"GND\g";
2"P3V3_STBY\g";
3"GND\g";
4"GND\g";
5"P3V3_STBY\g";
6"GND\g";
7"P12V_FAN\g";
8"P3V3_STBY\g";
9"GND\g";
10"P5V_STBY\g";
11"PUMP_TACH1_D";
12"P12V_PUMP";
13"PUMP_TACH1";
14"PUMP_PWM_OUT_BUF";
15"PUMP_PWM_OUT_R";
16"PUMP_TACH1_R";
17"PUMP_TACH0";
18"PUMP_TACH_R";
19"PUMP_TACH_D";
20"TP_PUMP";
21"PUMP_PWM_OUT";
%"CAP_A"
"1","(-1775,5825)","0","dev_discrete","I1";
;
TOLERANCE"10%"
VOLTAGE"16V"
MATERIAL"X7R"
LOCATION"C10W2"
PACK_TYPE"0402V"
PART_NUMBER"A36096-030"
VALUE"0.1UF"
CDS_LIB"dev_discrete"
BOM_COST"SM_THERM"
ROOM"CPU_FANS"
SEC_TYPE"0402V"
SEC"1"
CDS_LOCATION"C10W2"
CDS_SEC"1";
"B"
$PN"2"6;
"A"
$PN"1"12;
%"DIODE"
"4","(-3000,4625)","0","mstr_discrete","I10";
;
LOCATION"CR10W2"
VALUE"SDMK0340L"
PACK_TYPE"SM"
MATERIAL"EMPTY"
PART_NUMBER"H71799-001"
CDS_SEC"1"
CDS_LOCATION"CR10W2"
CDS_LIB"mstr_discrete"
BOM_COST"SM_THERM"
ROOM"CPU_FANS"
SEC_TYPE"SM"
SEC"1";
"A"
$PN"2"15;
"C"
$PN"1"10;
%"RES"
"2","(-3250,4650)","2","mstr_discrete","I11";
;
PART_NUMBER"G21796-072"
PACK_TYPE"0402"
MATERIAL"CHIP"
WATTAGE"1/16W"
LOCATION"R10W3"
TOLERANCE"1%"
VALUE"4.75K"
CDS_SEC"1"
CDS_LOCATION"R10W3"
ROOM"CPU_FANS"
BOM_COST"SM_THERM"
CDS_LIB"mstr_discrete"
SEC_TYPE"0402"
SEC"1";
"A"
$PN"1"10;
"B"
$PN"2"15;
%"DIODE"
"1","(-3200,5250)","0","mstr_discrete","I12";
;
PACK_TYPE"SM"
MATERIAL"IC"
VALUE"SDMK0340L"
LOCATION"CR10W1"
PART_NUMBER"H71799-001"
SEC_TYPE"SM"
SEC"1"
ROOM"CPU_FANS"
BOM_COST"SM_THERM"
CDS_LIB"mstr_discrete"
CDS_LOCATION"CR10W1"
CDS_SEC"1";
"C"
$PN"1"19;
"A"
$PN"2"18;
%"RES"
"1","(-4650,5250)","0","mstr_discrete","I13";
;
VALUE"100.0"
WATTAGE"1/16W"
LOCATION"R10W1"
TOLERANCE"1%"
MATERIAL"CHIP"
PART_NUMBER"G21796-017"
PACK_TYPE"0402"
CDS_SEC"1"
CDS_LOCATION"R10W1"
CDS_LIB"mstr_discrete"
BOM_COST"SM_THERM"
NO_XNET_CONNECTION"1"
ROOM"CPU_FANS"
SEC_TYPE"0402"
SEC"1";
"B"
$PN"2"18;
"A"
$PN"1"17;
%"RES"
"1","(-4650,4450)","0","mstr_discrete","I14";
;
TOLERANCE"1.0%"
PACK_TYPE"0402"
MATERIAL"CHIP"
LOCATION"R10W4"
VALUE"221"
WATTAGE"1/16W"
PART_NUMBER"G21796-271"
CDS_LIB"mstr_discrete"
BOM_COST"SM_THERM"
ROOM"CPU_FANS"
SEC_TYPE"0402"
SEC"1"
CDS_LOCATION"R10W4"
CDS_SEC"1";
"B"
$PN"2"15;
"A"
$PN"1"14;
%"RES"
"2","(-5300,5450)","0","mstr_discrete","I15";
;
LOCATION"R10W2"
WATTAGE"1/16W"
TOLERANCE"1%"
PACK_TYPE"0402"
MATERIAL"CHIP"
VALUE"4.75K"
PART_NUMBER"G21796-072"
CDS_SEC"1"
CDS_LOCATION"R10W2"
ROOM"CPU_FANS"
BOM_COST"SM_THERM"
CDS_LIB"mstr_discrete"
SEC_TYPE"0402"
SEC"1";
"A"
$PN"1"8;
"B"
$PN"2"17;
%"CAP_A"
"1","(-5175,5050)","2","dev_discrete","I16";
;
MATERIAL"X7R"
TOLERANCE"10%"
PACK_TYPE"0402V"
VALUE"0.01UF"
VOLTAGE"25V"
PART_NUMBER"A36096-045"
LOCATION"C10W3"
CDS_SEC"1"
CDS_LOCATION"C10W3"
BOM_COST"SM_THERM"
ROOM"CPU_FANS"
CDS_LIB"dev_discrete"
SEC_TYPE"0402V"
SEC"1";
"B"
$PN"2"1;
"A"
$PN"1"17;
%"GND"
"1","(-5175,4800)","0","mstr_symbols","I17";
;
VOLTAGE"0.0V"
SIZE"1B"
CDS_LIB"mstr_symbols"
BODY_TYPE"PLUMBING"
HDL_POWER"GND";
"A\NAC"1;
%"TTL1G07_A"
"1","(-6325,4450)","0","mstr_ttl","I19";
;
VALUE"74LVC1G07"
MATERIAL"IC"
POWER_GROUP"VCC=P3V3_STBY;GND=GND"
LOCATION"U10W1"
PART_NUMBER"C88419-001"
PACK_TYPE"SOP"
SEC"1"
SEC_TYPE"SOP"
ROOM"CPU_FANS"
BOM_COST"SM_THERM"
CDS_LIB"mstr_ttl"
CDS_LOCATION"U10W1"
CDS_SEC"1";
"Y"
$PN"4"14;
"A"
$PN"2"21;
%"P3V3_STBY"
"1","(-6650,5075)","0","mstr_symbols","I20";
;
VOLTAGE"3.3V"
SIZE"1B"
CDS_LIB"mstr_symbols"
BODY_TYPE"PLUMBING"
HDL_POWER"P3V3_STBY";
"G\NAC"2;
%"CAP_A"
"1","(-6650,4900)","0","dev_discrete","I21";
;
PACK_TYPE"0402V"
MATERIAL"X7R"
VOLTAGE"16V"
TOLERANCE"10%"
VALUE"0.1UF"
PART_NUMBER"A36096-030"
LOCATION"C10W4"
SEC"1"
SEC_TYPE"0402V"
ROOM"CPU_FANS"
BOM_COST"SM_THERM"
CDS_LIB"dev_discrete"
CDS_LOCATION"C10W4"
CDS_SEC"1";
"B"
$PN"2"3;
"A"
$PN"1"2;
%"GND"
"1","(-6650,4700)","2","mstr_symbols","I22";
;
VOLTAGE"0.0V"
SIZE"1B"
ROOM"PLD"
CDS_LIB"mstr_symbols"
BODY_TYPE"PLUMBING"
HDL_POWER"GND";
"A\NAC"3;
%"CONN6_C74770005"
"1","(-1550,5200)","0","mstr_conn","I25";
;
CDS_SEC"1"
MATERIAL"HDR"
LOCATION"J1B2"
PART_NUMBER"C74770-005"
VALUE"0.22UF"
TOLERANCE"10%"
PACK_TYPE"PIP"
VOLTAGE"16V"
SEC_TYPE"PIP"
BOM_COST"SM_THERM"
SEC"1"
ROOM"CPU_FANS"
CDS_LIB"mstr_conn"
CDS_LOCATION"J1B2";
"IO6"
$PN"6"20;
"IO5"
$PN"5"11;
"IO4"
$PN"4"15;
"IO3"
$PN"3"19;
"IO2"
$PN"2"12;
"IO1"
$PN"1"9;
%"DIODE"
"1","(-3200,3700)","0","mstr_discrete","I26";
;
PART_NUMBER"H71799-001"
LOCATION"CR10W3"
VALUE"SDMK0340L"
PACK_TYPE"SM"
MATERIAL"IC"
CDS_LOCATION"CR10W3"
CDS_SEC"1"
CDS_LIB"mstr_discrete"
BOM_COST"SM_THERM"
ROOM"CPU_FANS"
SEC"1"
SEC_TYPE"SM";
"C"
$PN"1"11;
"A"
$PN"2"16;
%"RES"
"1","(-4650,3700)","0","mstr_discrete","I27";
;
MATERIAL"CHIP"
TOLERANCE"1%"
LOCATION"R10W6"
PART_NUMBER"G21796-017"
VALUE"100.0"
WATTAGE"1/16W"
PACK_TYPE"0402"
CDS_LOCATION"R10W6"
CDS_SEC"1"
CDS_LIB"mstr_discrete"
BOM_COST"SM_THERM"
NO_XNET_CONNECTION"1"
ROOM"CPU_FANS"
SEC_TYPE"0402"
SEC"1";
"B"
$PN"2"16;
"A"
$PN"1"13;
%"CAP_A"
"1","(-5175,3500)","2","dev_discrete","I29";
;
VALUE"0.01UF"
PART_NUMBER"A36096-045"
MATERIAL"X7R"
VOLTAGE"25V"
LOCATION"C10W5"
TOLERANCE"10%"
PACK_TYPE"0402V"
CDS_LOCATION"C10W5"
SEC"1"
SEC_TYPE"0402V"
CDS_LIB"dev_discrete"
ROOM"CPU_FANS"
BOM_COST"SM_THERM"
CDS_SEC"1";
"B"
$PN"2"4;
"A"
$PN"1"13;
%"CAP"
"1","(-2075,5825)","0","mstr_discrete","I3";
;
VALUE"10UF"
VOLTAGE"16V"
LOCATION"C10W1"
TOLERANCE"10%"
MATERIAL"X6S"
PACK_TYPE"0805"
PART_NUMBER"C95333-007"
CDS_SEC"1"
CDS_LOCATION"C10W1"
SEC"1"
SEC_TYPE"0805"
BOM_COST"SM_THERM"
ROOM"CPU_FANS"
CDS_LIB"mstr_discrete";
"A"
$PN"1"12;
"B"
$PN"2"6;
%"GND"
"1","(-5175,3250)","0","mstr_symbols","I30";
;
CDS_LIB"mstr_symbols"
SIZE"1B"
VOLTAGE"0.0V"
BODY_TYPE"PLUMBING"
HDL_POWER"GND";
"A\NAC"4;
%"RES"
"2","(-5300,3900)","0","mstr_discrete","I31";
;
PART_NUMBER"G21796-072"
PACK_TYPE"0402"
TOLERANCE"1%"
MATERIAL"CHIP"
WATTAGE"1/16W"
VALUE"4.75K"
LOCATION"R10W7"
CDS_LOCATION"R10W7"
SEC"1"
SEC_TYPE"0402"
CDS_LIB"mstr_discrete"
BOM_COST"SM_THERM"
ROOM"CPU_FANS"
CDS_SEC"1";
"A"
$PN"1"5;
"B"
$PN"2"13;
%"P3V3_STBY"
"1","(-5300,4125)","0","mstr_symbols","I32";
;
CDS_LIB"mstr_symbols"
SIZE"1B"
VOLTAGE"3.3V"
BODY_TYPE"PLUMBING"
HDL_POWER"P3V3_STBY";
"G\NAC"5;
%"GND"
"1","(-2075,5475)","0","mstr_symbols","I4";
;
CDS_LIB"mstr_symbols"
SIZE"1B"
VOLTAGE"0.0V"
BODY_TYPE"PLUMBING"
HDL_POWER"GND";
"A\NAC"6;
%"RES"
"1","(-3025,6025)","0","mstr_discrete","I5";
;
PART_NUMBER"G22179-004"
TOLERANCE"5%"
MATERIAL"CHIP"
LOCATION"R10W5"
VALUE"0.0"
WATTAGE"1/8W"
PACK_TYPE"0805"
CDS_SEC"1"
CDS_LOCATION"R10W5"
ROOM"HOT_SWAP"
CDS_LIB"mstr_discrete"
SEC"1"
SEC_TYPE"0805";
"B"
$PN"2"12;
"A"
$PN"1"7;
%"P12V_FAN"
"1","(-3325,6125)","0","mstr_symbols","I6";
;
VOLTAGE"12.0V"
CDS_LIB"mstr_symbols"
BODY_TYPE"PLUMBING"
HDL_POWER"P12V_FAN";
"G\NAC"7;
%"P3V3_STBY"
"1","(-5300,5675)","0","mstr_symbols","I7";
;
VOLTAGE"3.3V"
SIZE"1B"
CDS_LIB"mstr_symbols"
BODY_TYPE"PLUMBING"
HDL_POWER"P3V3_STBY";
"G\NAC"8;
%"GND"
"1","(-1850,5350)","5","mstr_symbols","I8";
;
CDS_LIB"mstr_symbols"
VOLTAGE"0.0V"
SIZE"1B"
BODY_TYPE"PLUMBING"
HDL_POWER"GND";
"A\NAC"9;
%"P5V_STBY"
"1","(-3000,4925)","0","mstr_symbols","I9";
;
CDS_LIB"mstr_symbols"
SIZE"1B"
VOLTAGE"5.0V"
BODY_TYPE"PLUMBING"
HDL_POWER"P5V_STBY";
"G\NAC"10;
END.
